# T6G (Grand Teton) — schematic netlist excerpt (pin names and nets, part order shuffled) for the footprints in the layout excerpt that follows; sources: Cadence DE-HDL packaged netlist, KiCad conversion of 04192023_DAF0TMB3IC0_F0TG_MB_C_brd_V02_OCP.brd

PU43  ISL99390FRZTR5935  ISL99390FRZ-TR5935 IC  pkg QFN21_6X5XB  page 194
  VOS  = PVDDCR_CPU0_P0_VOS2
  AGND  = GND
  VCC  = PVDDCR_CPU0_P0_VCC2
  PVCC  = PVDDCR_CPU0_P0_PVCC
  PGND1  = GND
  GL1  = NC_PVDDCR_CPU0_P0_GL1_2
  PGND2  = GND
  SW  = SW_PVDDCR_CPU0_P0_SW2
  VIN1  = SW_P12V_AUX_PVDDCR_CPU0_P0_FLT
  VIN2  = SW_P12V_AUX_PVDDCR_CPU0_P0_FLT
  DNC  = NC_PVDDCR_CPU0_P0_DNC2
  PHASE  = SW_PVDDCR_CPU0_P0_PH2
  BOOT  = SW_PVDDCR_CPU0_P0_BOOT2
  PWM  = PVDDCR_CPU0_P0_PWM2
  EN  = PVDDCR_CPU0_P0_VCC2
  TOUT_FLT  = PVDDCR_CPU0_P0_TEMP0
  LSET  = PVDDCR_CPU0_P0_LSET2
  IOUT  = PVDDCR_CPU0_P0_IMON2
  REFIN  = PVDDCR_CPU0_P0_VCCS
  PGND3  = GND
  GL2  = NC_PVDDCR_CPU0_P0_GL2_2

(kicad_pcb
	(version 20260206)
	(generator "pcbnew")
	(generator_version "10.0")
	(general
		(thickness 1.6)
		(legacy_teardrops no)
	)
	(paper "A4")
	(title_block
		(title "04192023_DAF0TMB3IC0_F0TG_MB_C_brd_V02_OCP.brd")
		(comment 1 "Grand Teton / footprints 1028-1028 of 8354")
	)
	(layers
		(0 "F.Cu" signal "TOP")
		(4 "In1.Cu" signal "GND")
		(6 "In2.Cu" signal "IN1")
		(8 "In3.Cu" signal "GND1")
		(10 "In4.Cu" signal "IN2")
		(12 "In5.Cu" signal "GND2")
		(14 "In6.Cu" signal "IN3")
		(16 "In7.Cu" signal "GND3")
		(18 "In8.Cu" signal "VCC")
		(20 "In9.Cu" signal "VCC1")
		(22 "In10.Cu" signal "GND4")
		(24 "In11.Cu" signal "IN4")
		(26 "In12.Cu" signal "GND5")
		(28 "In13.Cu" signal "IN5")
		(30 "In14.Cu" signal "GND6")
		(32 "In15.Cu" signal "IN6")
		(34 "In16.Cu" signal "GND7")
		(2 "B.Cu" signal "BOTTOM")
		(9 "F.Adhes" user "F.Adhesive")
		(11 "B.Adhes" user "B.Adhesive")
		(13 "F.Paste" user "Package Geometry/Pastemask Top")
		(15 "B.Paste" user "Package Geometry/Pastemask Bottom")
		(5 "F.SilkS" user "Ref Des/Silkscreen Top")
		(7 "B.SilkS" user "Ref Des/Silkscreen Bottom")
		(1 "F.Mask" user "Board Geometry/Soldermask Top")
		(3 "B.Mask" user "Board Geometry/Soldermask Bottom")
		(17 "Dwgs.User" user "User.Drawings")
		(19 "Cmts.User" user "User.Comments")
		(21 "Eco1.User" user "User.Eco1")
		(23 "Eco2.User" user "User.Eco2")
		(25 "Edge.Cuts" user "Board Geometry/Outline")
		(27 "Margin" user)
		(31 "F.CrtYd" user "Package Geometry/Place Bound Top")
		(29 "B.CrtYd" user "Package Geometry/Place Bound Bottom")
		(35 "F.Fab" user "Ref Des/Assembly Top")
		(33 "B.Fab" user "Ref Des/Assembly Bottom")
	)
	(footprint ""
		(layer "F.Cu")
		(at 372.67515 -182.743856 180)
		(property "Reference" "PU43"
			(at -0.013208 -7.145274 0)
			(unlocked yes)
			(layer "F.SilkS")
			(effects
				(font
					(size 0.7874 0.5842)
					(thickness 0.1524)
				)
				(justify left)
			)
		)
		(property "Value" ""
			(at 0 0 180)
			(layer "F.Fab")
			(effects
				(font
					(size 1.27 1.27)
				)
			)
		)
		(duplicate_pad_numbers_are_jumpers no)
		(fp_line
			(start 2.500122 2.999994)
			(end 2.2987 2.999994)
			(stroke
				(width 0.1524)
				(type default)
			)
			(layer "F.SilkS")
		)
		(fp_line
			(start 2.500122 2.339594)
			(end 2.500122 2.999994)
			(stroke
				(width 0.1524)
				(type default)
			)
			(layer "F.SilkS")
		)
		(fp_line
			(start 2.500122 -2.999994)
			(end 2.500122 -2.44348)
			(stroke
				(width 0.1524)
				(type default)
			)
			(layer "F.SilkS")
		)
		(fp_line
			(start 2.31394 -2.999994)
			(end 2.500122 -2.999994)
			(stroke
				(width 0.1524)
				(type default)
			)
			(layer "F.SilkS")
		)
		(fp_line
			(start -2.2987 2.999994)
			(end -2.500122 2.999994)
			(stroke
				(width 0.1524)
				(type default)
			)
			(layer "F.SilkS")
		)
		(fp_line
			(start -2.500122 2.999994)
			(end -2.500122 2.339594)
			(stroke
				(width 0.1524)
				(type default)
			)
			(layer "F.SilkS")
		)
		(fp_line
			(start -2.500122 0.6604)
			(end -2.500122 0.229108)
			(stroke
				(width 0.1524)
				(type default)
			)
			(layer "F.SilkS")
		)
		(fp_line
			(start -2.500122 -2.529078)
			(end -2.500122 -2.999994)
			(stroke
				(width 0.1524)
				(type default)
			)
			(layer "F.SilkS")
		)
		(fp_line
			(start -2.500122 -2.999994)
			(end -2.24409 -2.999994)
			(stroke
				(width 0.1524)
				(type default)
			)
			(layer "F.SilkS")
		)
		(fp_poly
			(pts
				(xy -2.755138 -2.475484) (xy -3.387598 -2.686304) (xy -2.965958 -3.108198)
			)
			(stroke
				(width 0)
				(type default)
			)
			(fill yes)
			(layer "F.SilkS")
		)
		(fp_line
			(start 2.500122 2.999994)
			(end -2.500122 2.999994)
			(stroke
				(width 0.1)
				(type default)
			)
			(layer "F.Fab")
		)
		(fp_line
			(start 2.500122 -2.999994)
			(end 2.500122 2.999994)
			(stroke
				(width 0.1)
				(type default)
			)
			(layer "F.Fab")
		)
		(fp_line
			(start -2.500122 2.999994)
			(end -2.500122 -2.999994)
			(stroke
				(width 0.1)
				(type default)
			)
			(layer "F.Fab")
		)
		(fp_line
			(start -2.500122 -2.999994)
			(end 2.500122 -2.999994)
			(stroke
				(width 0.1)
				(type default)
			)
			(layer "F.Fab")
		)
		(fp_poly
			(pts
				(xy -4.218432 -2.783078) (xy -4.218432 -1.767078) (xy -3.202432 -2.275078)
			)
			(stroke
				(width 0)
				(type default)
			)
			(fill yes)
			(layer "F.Fab")
		)
		(pad "1" smd rect
			(at -2.400046 -2.275078 270)
			(size 0.2286 0.6096)
			(layers "F.Cu" "F.Mask" "F.Paste")
			(net "PVDDCR_CPU0_P0_VOS2")
		)
		(pad "2" smd rect
			(at -2.400046 -1.82499 270)
			(size 0.2286 0.6096)
			(layers "F.Cu" "F.Mask" "F.Paste")
			(net "GND")
		)
		(pad "3" smd rect
			(at -2.400046 -1.374902 270)
			(size 0.2286 0.6096)
			(layers "F.Cu" "F.Mask" "F.Paste")
			(net "PVDDCR_CPU0_P0_VCC2")
		)
		(pad "4" smd rect
			(at -2.400046 -0.925068 270)
			(size 0.2286 0.6096)
			(layers "F.Cu" "F.Mask" "F.Paste")
			(net "PVDDCR_CPU0_P0_PVCC")
		)
		(pad "5" smd rect
			(at -2.400046 -0.47498 270)
			(size 0.2286 0.6096)
			(layers "F.Cu" "F.Mask" "F.Paste")
			(net "GND")
		)
		(pad "6" smd rect
			(at -2.400046 -0.024892 270)
			(size 0.2286 0.6096)
			(layers "F.Cu" "F.Mask" "F.Paste")
			(net "NC_PVDDCR_CPU0_P0_GL1_2")
		)
		(pad "7_9-20_24" smd circle
			(at 0 1.150112 270)
			(size 0 0)
			(layers "F.Cu" "F.Mask" "F.Paste")
			(net "GND")
		)
		(pad "10_19" smd rect
			(at 0 2.899918 270)
			(size 0.6096 4.318)
			(layers "F.Cu" "F.Mask" "F.Paste")
			(net "SW_PVDDCR_CPU0_P0_SW2")
		)
		(pad "25_29" smd rect
			(at 1.549908 -1.279906 90)
			(size 2.0574 2.3114)
			(layers "F.Cu" "F.Mask" "F.Paste")
			(net "SW_P12V_AUX_PVDDCR_CPU0_P0_FLT")
		)
		(pad "30" smd rect
			(at 2.05994 -2.899918 180)
			(size 0.2286 0.6096)
			(layers "F.Cu" "F.Mask" "F.Paste")
			(net "SW_P12V_AUX_PVDDCR_CPU0_P0_FLT")
		)
		(pad "31" smd rect
			(at 1.610106 -2.899918 180)
			(size 0.2286 0.6096)
			(layers "F.Cu" "F.Mask" "F.Paste")
			(net "NC_PVDDCR_CPU0_P0_DNC2")
		)
		(pad "32" smd rect
			(at 1.160018 -2.899918 180)
			(size 0.2286 0.6096)
			(layers "F.Cu" "F.Mask" "F.Paste")
			(net "SW_PVDDCR_CPU0_P0_PH2")
		)
		(pad "33" smd rect
			(at 0.70993 -2.899918 180)
			(size 0.2286 0.6096)
			(layers "F.Cu" "F.Mask" "F.Paste")
			(net "SW_PVDDCR_CPU0_P0_BOOT2")
		)
		(pad "34" smd rect
			(at 0.260096 -2.899918 180)
			(size 0.2286 0.6096)
			(layers "F.Cu" "F.Mask" "F.Paste")
			(net "PVDDCR_CPU0_P0_PWM2")
		)
		(pad "35" smd rect
			(at -0.189992 -2.899918 180)
			(size 0.2286 0.6096)
			(layers "F.Cu" "F.Mask" "F.Paste")
			(net "PVDDCR_CPU0_P0_VCC2")
		)
		(pad "36" smd rect
			(at -0.64008 -2.899918 180)
			(size 0.2286 0.6096)
			(layers "F.Cu" "F.Mask" "F.Paste")
			(net "PVDDCR_CPU0_P0_TEMP0")
		)
		(pad "37" smd rect
			(at -1.089914 -2.899918 180)
			(size 0.2286 0.6096)
			(layers "F.Cu" "F.Mask" "F.Paste")
			(net "PVDDCR_CPU0_P0_LSET2")
		)
		(pad "38" smd rect
			(at -1.540002 -2.899918 180)
			(size 0.2286 0.6096)
			(layers "F.Cu" "F.Mask" "F.Paste")
			(net "PVDDCR_CPU0_P0_IMON2")
		)
		(pad "39" smd rect
			(at -1.99009 -2.899918 180)
			(size 0.2286 0.6096)
			(layers "F.Cu" "F.Mask" "F.Paste")
			(net "PVDDCR_CPU0_P0_VCCS")
		)
		(pad "40" smd rect
			(at -0.87503 -1.27508 180)
			(size 1.7526 1.9558)
			(layers "F.Cu" "F.Mask" "F.Paste")
			(net "GND")
		)
		(pad "41" smd rect
			(at -1.525016 0.249936 90)
			(size 0.3048 0.4572)
			(layers "F.Cu" "F.Mask" "F.Paste")
			(net "NC_PVDDCR_CPU0_P0_GL2_2")
		)
		(zone
			(layer "F.Cu")
			(hatch none 0.5)
			(connect_pads
				(clearance 0)
			)
			(min_thickness 0.25)
			(keepout
				(tracks not_allowed)
				(vias allowed)
				(pads allowed)
				(copperpour not_allowed)
				(footprints allowed)
			)
			(placement
				(enabled no)
				(sheetname "")
			)
			(fill
				(thermal_gap 0.5)
				(thermal_bridge_width 0.5)
				(island_removal_mode 0)
			)
			(polygon
				(pts
					(xy 375.175272 -185.32729) (xy 375.175272 -184.99455) (xy 370.175028 -184.99455) (xy 370.175028 -185.318654)
					(xy 370.46535 -185.318654) (xy 370.46535 -185.288174) (xy 374.88495 -185.288174) (xy 374.88495 -185.32729)
				)
			)
		)
		(zone
			(layer "F.Cu")
			(hatch none 0.5)
			(connect_pads
				(clearance 0)
			)
			(min_thickness 0.25)
			(keepout
				(tracks not_allowed)
				(vias allowed)
				(pads allowed)
				(copperpour not_allowed)
				(footprints allowed)
			)
			(placement
				(enabled no)
				(sheetname "")
			)
			(fill
				(thermal_gap 0.5)
				(thermal_bridge_width 0.5)
				(island_removal_mode 0)
			)
			(polygon
				(pts
					(xy 372.62308 -182.497476) (xy 372.62308 -180.440076) (xy 374.47728 -180.440076) (xy 374.47728 -180.681122)
					(xy 374.719596 -180.681122) (xy 374.719596 -180.199538) (xy 370.902484 -180.199538) (xy 370.902484 -180.38445)
					(xy 372.331742 -180.38445) (xy 372.331742 -182.54345) (xy 370.175028 -182.54345) (xy 370.175028 -182.793132)
					(xy 372.327424 -182.793132)
				)
			)
		)
	)
)
